# T6G (Grand Teton) — schematic netlist excerpt (pin names and nets, part order shuffled) for the footprints in the layout excerpt that follows; sources: Cadence DE-HDL packaged netlist, KiCad conversion of 04192023_DAF0TMB3IC0_F0TG_MB_C_brd_V02_OCP.brd

C157  Q_CAP  10UF 25V 10% X6S  pkg C0805  page 92 : A = P12V_MEM_CPU0 ; B = GND
R1697  Q_RES  10 1% CHIP  pkg 0402LF  page 100 : A = I3C_SPD_DDRAF_CPU1_SDA ; B = I3C_SPD_DDRC_CPU1_SDA
C153  Q_CAP  10UF 25V 10% X6S  pkg C0805  page 90 : A = P12V_MEM_CPU0 ; B = GND

(kicad_pcb
	(version 20260206)
	(generator "pcbnew")
	(generator_version "10.0")
	(general
		(thickness 1.6)
		(legacy_teardrops no)
	)
	(paper "A4")
	(title_block
		(title "04192023_DAF0TMB3IC0_F0TG_MB_C_brd_V02_OCP.brd")
		(comment 1 "Grand Teton / footprints 6268-6270 of 8354")
	)
	(layers
		(0 "F.Cu" signal "TOP")
		(4 "In1.Cu" signal "GND")
		(6 "In2.Cu" signal "IN1")
		(8 "In3.Cu" signal "GND1")
		(10 "In4.Cu" signal "IN2")
		(12 "In5.Cu" signal "GND2")
		(14 "In6.Cu" signal "IN3")
		(16 "In7.Cu" signal "GND3")
		(18 "In8.Cu" signal "VCC")
		(20 "In9.Cu" signal "VCC1")
		(22 "In10.Cu" signal "GND4")
		(24 "In11.Cu" signal "IN4")
		(26 "In12.Cu" signal "GND5")
		(28 "In13.Cu" signal "IN5")
		(30 "In14.Cu" signal "GND6")
		(32 "In15.Cu" signal "IN6")
		(34 "In16.Cu" signal "GND7")
		(2 "B.Cu" signal "BOTTOM")
		(9 "F.Adhes" user "F.Adhesive")
		(11 "B.Adhes" user "B.Adhesive")
		(13 "F.Paste" user "Package Geometry/Pastemask Top")
		(15 "B.Paste" user "Package Geometry/Pastemask Bottom")
		(5 "F.SilkS" user "Ref Des/Silkscreen Top")
		(7 "B.SilkS" user "Ref Des/Silkscreen Bottom")
		(1 "F.Mask" user "Board Geometry/Soldermask Top")
		(3 "B.Mask" user "Board Geometry/Soldermask Bottom")
		(17 "Dwgs.User" user "User.Drawings")
		(19 "Cmts.User" user "User.Comments")
		(21 "Eco1.User" user "User.Eco1")
		(23 "Eco2.User" user "User.Eco2")
		(25 "Edge.Cuts" user "Board Geometry/Outline")
		(27 "Margin" user)
		(31 "F.CrtYd" user "Package Geometry/Place Bound Top")
		(29 "B.CrtYd" user "Package Geometry/Place Bound Bottom")
		(35 "F.Fab" user "Ref Des/Assembly Top")
		(33 "B.Fab" user "Ref Des/Assembly Bottom")
	)
	(footprint ""
		(layer "B.Cu")
		(at 43.576748 -195.901564 180)
		(property "Reference" "R1697"
			(at 0 0 0)
			(layer "B.SilkS")
			(hide yes)
			(effects
				(font
					(size 1.27 1.27)
				)
				(justify mirror)
			)
		)
		(property "Value" ""
			(at 0 0 0)
			(layer "B.Fab")
			(effects
				(font
					(size 1.27 1.27)
				)
				(justify mirror)
			)
		)
		(duplicate_pad_numbers_are_jumpers no)
		(fp_line
			(start 0.7874 0.4064)
			(end 0.7874 -0.4064)
			(stroke
				(width 0.1524)
				(type default)
			)
			(layer "B.SilkS")
		)
		(fp_line
			(start 0.7874 -0.4064)
			(end -0.7874 -0.4064)
			(stroke
				(width 0.1524)
				(type default)
			)
			(layer "B.SilkS")
		)
		(fp_line
			(start -0.7874 0.4064)
			(end 0.7874 0.4064)
			(stroke
				(width 0.1524)
				(type default)
			)
			(layer "B.SilkS")
		)
		(fp_line
			(start -0.7874 -0.4064)
			(end -0.7874 0.4064)
			(stroke
				(width 0.1524)
				(type default)
			)
			(layer "B.SilkS")
		)
		(fp_line
			(start 0.67945 0.3048)
			(end 0.67945 -0.305054)
			(stroke
				(width 0.1)
				(type default)
			)
			(layer "B.Fab")
		)
		(fp_line
			(start 0.67945 -0.305054)
			(end 0.12065 -0.305054)
			(stroke
				(width 0.1)
				(type default)
			)
			(layer "B.Fab")
		)
		(fp_line
			(start 0.12065 0.3048)
			(end 0.67945 0.3048)
			(stroke
				(width 0.1)
				(type default)
			)
			(layer "B.Fab")
		)
		(fp_line
			(start 0.12065 0.2794)
			(end 0.12065 0.3048)
			(stroke
				(width 0.1)
				(type default)
			)
			(layer "B.Fab")
		)
		(fp_line
			(start 0.12065 -0.2794)
			(end -0.12065 -0.2794)
			(stroke
				(width 0.1)
				(type default)
			)
			(layer "B.Fab")
		)
		(fp_line
			(start 0.12065 -0.305054)
			(end 0.12065 -0.2794)
			(stroke
				(width 0.1)
				(type default)
			)
			(layer "B.Fab")
		)
		(fp_line
			(start -0.120396 0.3048)
			(end -0.120396 0.2794)
			(stroke
				(width 0.1)
				(type default)
			)
			(layer "B.Fab")
		)
		(fp_line
			(start -0.120396 0.2794)
			(end 0.12065 0.2794)
			(stroke
				(width 0.1)
				(type default)
			)
			(layer "B.Fab")
		)
		(fp_line
			(start -0.12065 -0.2794)
			(end -0.12065 -0.3048)
			(stroke
				(width 0.1)
				(type default)
			)
			(layer "B.Fab")
		)
		(fp_line
			(start -0.12065 -0.3048)
			(end -0.67945 -0.3048)
			(stroke
				(width 0.1)
				(type default)
			)
			(layer "B.Fab")
		)
		(fp_line
			(start -0.67945 0.3048)
			(end -0.120396 0.3048)
			(stroke
				(width 0.1)
				(type default)
			)
			(layer "B.Fab")
		)
		(fp_line
			(start -0.67945 -0.3048)
			(end -0.67945 0.3048)
			(stroke
				(width 0.1)
				(type default)
			)
			(layer "B.Fab")
		)
		(pad "1" smd circle
			(at 0.40005 0)
			(size 0 0)
			(layers "B.Cu" "B.Mask" "B.Paste")
			(net "I3C_SPD_DDRAF_CPU1_SDA")
		)
		(pad "2" smd circle
			(at -0.40005 0)
			(size 0 0)
			(layers "B.Cu" "B.Mask" "B.Paste")
			(net "I3C_SPD_DDRC_CPU1_SDA")
		)
	)
	(footprint ""
		(layer "B.Cu")
		(at 273.092164 -192.660016 180)
		(property "Reference" "C153"
			(at 0 0 0)
			(layer "B.SilkS")
			(hide yes)
			(effects
				(font
					(size 1.27 1.27)
				)
				(justify mirror)
			)
		)
		(property "Value" ""
			(at 0 0 0)
			(layer "B.Fab")
			(effects
				(font
					(size 1.27 1.27)
				)
				(justify mirror)
			)
		)
		(duplicate_pad_numbers_are_jumpers no)
		(fp_line
			(start 1.524 0.762)
			(end 1.524 -0.762)
			(stroke
				(width 0.1524)
				(type default)
			)
			(layer "B.SilkS")
		)
		(fp_line
			(start 1.524 -0.762)
			(end -1.524 -0.762)
			(stroke
				(width 0.1524)
				(type default)
			)
			(layer "B.SilkS")
		)
		(fp_line
			(start -1.524 0.762)
			(end 1.524 0.762)
			(stroke
				(width 0.1524)
				(type default)
			)
			(layer "B.SilkS")
		)
		(fp_line
			(start -1.524 -0.762)
			(end -1.524 0.762)
			(stroke
				(width 0.1524)
				(type default)
			)
			(layer "B.SilkS")
		)
		(fp_line
			(start 1.1049 0.724916)
			(end -1.1049 0.724916)
			(stroke
				(width 0.1)
				(type default)
			)
			(layer "B.Fab")
		)
		(fp_line
			(start 1.1049 -0.724916)
			(end 1.1049 0.724916)
			(stroke
				(width 0.1)
				(type default)
			)
			(layer "B.Fab")
		)
		(fp_line
			(start -1.1049 0.724916)
			(end -1.1049 -0.724916)
			(stroke
				(width 0.1)
				(type default)
			)
			(layer "B.Fab")
		)
		(fp_line
			(start -1.1049 -0.724916)
			(end 1.1049 -0.724916)
			(stroke
				(width 0.1)
				(type default)
			)
			(layer "B.Fab")
		)
		(pad "1" smd rect
			(at 0.889 0 180)
			(size 1.016 1.27)
			(layers "B.Cu" "B.Mask" "B.Paste")
			(net "P12V_MEM_CPU0")
		)
		(pad "2" smd rect
			(at -0.889 0 180)
			(size 1.016 1.27)
			(layers "B.Cu" "B.Mask" "B.Paste")
			(net "GND")
		)
	)
	(footprint ""
		(layer "B.Cu")
		(at 412.367984 -192.660016 180)
		(property "Reference" "C157"
			(at 0 0 0)
			(layer "B.SilkS")
			(hide yes)
			(effects
				(font
					(size 1.27 1.27)
				)
				(justify mirror)
			)
		)
		(property "Value" ""
			(at 0 0 0)
			(layer "B.Fab")
			(effects
				(font
					(size 1.27 1.27)
				)
				(justify mirror)
			)
		)
		(duplicate_pad_numbers_are_jumpers no)
		(fp_line
			(start 1.524 0.762)
			(end 1.524 -0.762)
			(stroke
				(width 0.1524)
				(type default)
			)
			(layer "B.SilkS")
		)
		(fp_line
			(start 1.524 -0.762)
			(end -1.524 -0.762)
			(stroke
				(width 0.1524)
				(type default)
			)
			(layer "B.SilkS")
		)
		(fp_line
			(start -1.524 0.762)
			(end 1.524 0.762)
			(stroke
				(width 0.1524)
				(type default)
			)
			(layer "B.SilkS")
		)
		(fp_line
			(start -1.524 -0.762)
			(end -1.524 0.762)
			(stroke
				(width 0.1524)
				(type default)
			)
			(layer "B.SilkS")
		)
		(fp_line
			(start 1.1049 0.724916)
			(end -1.1049 0.724916)
			(stroke
				(width 0.1)
				(type default)
			)
			(layer "B.Fab")
		)
		(fp_line
			(start 1.1049 -0.724916)
			(end 1.1049 0.724916)
			(stroke
				(width 0.1)
				(type default)
			)
			(layer "B.Fab")
		)
		(fp_line
			(start -1.1049 0.724916)
			(end -1.1049 -0.724916)
			(stroke
				(width 0.1)
				(type default)
			)
			(layer "B.Fab")
		)
		(fp_line
			(start -1.1049 -0.724916)
			(end 1.1049 -0.724916)
			(stroke
				(width 0.1)
				(type default)
			)
			(layer "B.Fab")
		)
		(pad "1" smd rect
			(at 0.889 0 180)
			(size 1.016 1.27)
			(layers "B.Cu" "B.Mask" "B.Paste")
			(net "P12V_MEM_CPU0")
		)
		(pad "2" smd rect
			(at -0.889 0 180)
			(size 1.016 1.27)
			(layers "B.Cu" "B.Mask" "B.Paste")
			(net "GND")
		)
	)
)
